(kicad_pcb
	(version 20260206)
	(generator "pcbnew")
	(generator_version "10.0")
	(general
		(thickness 1.6)
		(legacy_teardrops no)
	)
	(paper "A4")
	(title_block
		(title "03242023_DA0F0TMBIJ0_F0T_Motherboard_J_brd_V01_OCP.brd")
		(comment 1 "Grand Teton / footprints 2980-2985 of 6105")
	)
	(layers
		(0 "F.Cu" signal "TOP")
		(4 "In1.Cu" signal "GND")
		(6 "In2.Cu" signal "IN1")
		(8 "In3.Cu" signal "GND1")
		(10 "In4.Cu" signal "IN2")
		(12 "In5.Cu" signal "GND2")
		(14 "In6.Cu" signal "IN3")
		(16 "In7.Cu" signal "GND3")
		(18 "In8.Cu" signal "VCC")
		(20 "In9.Cu" signal "VCC1")
		(22 "In10.Cu" signal "GND4")
		(24 "In11.Cu" signal "IN4")
		(26 "In12.Cu" signal "GND5")
		(28 "In13.Cu" signal "IN5")
		(30 "In14.Cu" signal "GND6")
		(32 "In15.Cu" signal "IN6")
		(34 "In16.Cu" signal "GND7")
		(2 "B.Cu" signal "BOTTOM")
		(9 "F.Adhes" user "F.Adhesive")
		(11 "B.Adhes" user "B.Adhesive")
		(13 "F.Paste" user "Package Geometry/Pastemask Top")
		(15 "B.Paste" user "Package Geometry/Pastemask Bottom")
		(5 "F.SilkS" user "Ref Des/Silkscreen Top")
		(7 "B.SilkS" user "Ref Des/Silkscreen Bottom")
		(1 "F.Mask" user "Board Geometry/Soldermask Top")
		(3 "B.Mask" user "Board Geometry/Soldermask Bottom")
		(17 "Dwgs.User" user "User.Drawings")
		(19 "Cmts.User" user "User.Comments")
		(21 "Eco1.User" user "User.Eco1")
		(23 "Eco2.User" user "User.Eco2")
		(25 "Edge.Cuts" user "Board Geometry/Outline")
		(27 "Margin" user)
		(31 "F.CrtYd" user "Package Geometry/Place Bound Top")
		(29 "B.CrtYd" user "Package Geometry/Place Bound Bottom")
		(35 "F.Fab" user "Ref Des/Assembly Top")
		(33 "B.Fab" user "Ref Des/Assembly Bottom")
	)
	(footprint ""
		(layer "F.Cu")
		(at 98.1329 -413.273748)
		(property "Reference" "R4544"
			(at 0 0 0)
			(layer "F.SilkS")
			(hide yes)
			(effects
				(font
					(size 1.27 1.27)
				)
			)
		)
		(property "Value" ""
			(at 0 0 0)
			(layer "F.Fab")
			(effects
				(font
					(size 1.27 1.27)
				)
			)
		)
		(duplicate_pad_numbers_are_jumpers no)
		(fp_line
			(start -0.7874 -0.4064)
			(end 0.7874 -0.4064)
			(stroke
				(width 0.1524)
				(type default)
			)
			(layer "F.SilkS")
		)
		(fp_line
			(start -0.7874 0.4064)
			(end -0.7874 -0.4064)
			(stroke
				(width 0.1524)
				(type default)
			)
			(layer "F.SilkS")
		)
		(fp_line
			(start 0.7874 -0.4064)
			(end 0.7874 0.4064)
			(stroke
				(width 0.1524)
				(type default)
			)
			(layer "F.SilkS")
		)
		(fp_line
			(start 0.7874 0.4064)
			(end -0.7874 0.4064)
			(stroke
				(width 0.1524)
				(type default)
			)
			(layer "F.SilkS")
		)
		(fp_line
			(start -0.67945 -0.305054)
			(end -0.12065 -0.305054)
			(stroke
				(width 0.1)
				(type default)
			)
			(layer "F.Fab")
		)
		(fp_line
			(start -0.67945 0.3048)
			(end -0.67945 -0.305054)
			(stroke
				(width 0.1)
				(type default)
			)
			(layer "F.Fab")
		)
		(fp_line
			(start -0.12065 -0.305054)
			(end -0.12065 -0.2794)
			(stroke
				(width 0.1)
				(type default)
			)
			(layer "F.Fab")
		)
		(fp_line
			(start -0.12065 -0.2794)
			(end 0.12065 -0.2794)
			(stroke
				(width 0.1)
				(type default)
			)
			(layer "F.Fab")
		)
		(fp_line
			(start -0.12065 0.2794)
			(end -0.12065 0.3048)
			(stroke
				(width 0.1)
				(type default)
			)
			(layer "F.Fab")
		)
		(fp_line
			(start -0.12065 0.3048)
			(end -0.67945 0.3048)
			(stroke
				(width 0.1)
				(type default)
			)
			(layer "F.Fab")
		)
		(fp_line
			(start 0.120396 0.2794)
			(end -0.12065 0.2794)
			(stroke
				(width 0.1)
				(type default)
			)
			(layer "F.Fab")
		)
		(fp_line
			(start 0.120396 0.3048)
			(end 0.120396 0.2794)
			(stroke
				(width 0.1)
				(type default)
			)
			(layer "F.Fab")
		)
		(fp_line
			(start 0.12065 -0.3048)
			(end 0.67945 -0.3048)
			(stroke
				(width 0.1)
				(type default)
			)
			(layer "F.Fab")
		)
		(fp_line
			(start 0.12065 -0.2794)
			(end 0.12065 -0.3048)
			(stroke
				(width 0.1)
				(type default)
			)
			(layer "F.Fab")
		)
		(fp_line
			(start 0.67945 -0.3048)
			(end 0.67945 0.3048)
			(stroke
				(width 0.1)
				(type default)
			)
			(layer "F.Fab")
		)
		(fp_line
			(start 0.67945 0.3048)
			(end 0.120396 0.3048)
			(stroke
				(width 0.1)
				(type default)
			)
			(layer "F.Fab")
		)
		(pad "1" smd circle
			(at -0.40005 0)
			(size 0 0)
			(layers "F.Cu" "F.Mask" "F.Paste")
			(net "HGX_DETECT_N")
		)
		(pad "2" smd circle
			(at 0.40005 0)
			(size 0 0)
			(layers "F.Cu" "F.Mask" "F.Paste")
			(net "GND")
		)
	)
	(footprint ""
		(layer "F.Cu")
		(at 77.780896 -70.78599)
		(property "Reference" "D66"
			(at -40.319706 50.178462 90)
			(unlocked yes)
			(layer "F.SilkS")
			(effects
				(font
					(size 0.635 0.4064)
					(thickness 0.1524)
				)
				(justify left)
			)
		)
		(property "Value" ""
			(at 0 0 0)
			(layer "F.Fab")
			(effects
				(font
					(size 1.27 1.27)
				)
			)
		)
		(duplicate_pad_numbers_are_jumpers no)
		(fp_line
			(start -0.90678 0.4826)
			(end -0.90678 -0.4699)
			(stroke
				(width 0.1524)
				(type default)
			)
			(layer "F.SilkS")
		)
		(fp_line
			(start -0.89408 -0.4826)
			(end 0.90678 -0.4826)
			(stroke
				(width 0.1524)
				(type default)
			)
			(layer "F.SilkS")
		)
		(fp_line
			(start -0.79248 -0.4826)
			(end 1.03378 -0.4826)
			(stroke
				(width 0.1524)
				(type default)
			)
			(layer "F.SilkS")
		)
		(fp_line
			(start -0.64008 -0.4826)
			(end 1.16078 -0.4826)
			(stroke
				(width 0.1524)
				(type default)
			)
			(layer "F.SilkS")
		)
		(fp_line
			(start 0.90678 -0.4826)
			(end 0.90678 0.4826)
			(stroke
				(width 0.1524)
				(type default)
			)
			(layer "F.SilkS")
		)
		(fp_line
			(start 0.90678 0.4826)
			(end -0.90678 0.4826)
			(stroke
				(width 0.1524)
				(type default)
			)
			(layer "F.SilkS")
		)
		(fp_line
			(start 1.03378 -0.4826)
			(end 1.03378 0.4826)
			(stroke
				(width 0.1524)
				(type default)
			)
			(layer "F.SilkS")
		)
		(fp_line
			(start 1.03378 0.4826)
			(end -0.79248 0.4826)
			(stroke
				(width 0.1524)
				(type default)
			)
			(layer "F.SilkS")
		)
		(fp_line
			(start 1.16078 -0.4826)
			(end 1.16078 0.4826)
			(stroke
				(width 0.1524)
				(type default)
			)
			(layer "F.SilkS")
		)
		(fp_line
			(start 1.16078 0.4826)
			(end -0.64008 0.4826)
			(stroke
				(width 0.1524)
				(type default)
			)
			(layer "F.SilkS")
		)
		(fp_line
			(start -0.499872 -0.249936)
			(end 0.499872 -0.249936)
			(stroke
				(width 0.1)
				(type default)
			)
			(layer "F.Fab")
		)
		(fp_line
			(start -0.499872 0.249936)
			(end -0.499872 -0.249936)
			(stroke
				(width 0.1)
				(type default)
			)
			(layer "F.Fab")
		)
		(fp_line
			(start 0.499872 -0.249936)
			(end 0.499872 0.249936)
			(stroke
				(width 0.1)
				(type default)
			)
			(layer "F.Fab")
		)
		(fp_line
			(start 0.499872 0.249936)
			(end -0.499872 0.249936)
			(stroke
				(width 0.1)
				(type default)
			)
			(layer "F.Fab")
		)
		(pad "A" smd rect
			(at -0.47498 0)
			(size 0.6096 0.7112)
			(layers "F.Cu" "F.Mask" "F.Paste")
			(net "LED_RST_PLD_CPU0_DRAM_CD_N")
		)
		(pad "C" smd rect
			(at 0.47498 0)
			(size 0.6096 0.7112)
			(layers "F.Cu" "F.Mask" "F.Paste")
			(net "LED_RST_PLD_CPU0_DRAM_CD_N_D")
		)
	)
	(footprint ""
		(layer "F.Cu")
		(at 369.292632 -397.519398)
		(property "Reference" "R2725"
			(at 0 0 0)
			(layer "F.SilkS")
			(hide yes)
			(effects
				(font
					(size 1.27 1.27)
				)
			)
		)
		(property "Value" ""
			(at 0 0 0)
			(layer "F.Fab")
			(effects
				(font
					(size 1.27 1.27)
				)
			)
		)
		(duplicate_pad_numbers_are_jumpers no)
		(fp_line
			(start -0.7874 -0.4064)
			(end 0.7874 -0.4064)
			(stroke
				(width 0.1524)
				(type default)
			)
			(layer "F.SilkS")
		)
		(fp_line
			(start -0.7874 0.4064)
			(end -0.7874 -0.4064)
			(stroke
				(width 0.1524)
				(type default)
			)
			(layer "F.SilkS")
		)
		(fp_line
			(start 0.7874 -0.4064)
			(end 0.7874 0.4064)
			(stroke
				(width 0.1524)
				(type default)
			)
			(layer "F.SilkS")
		)
		(fp_line
			(start 0.7874 0.4064)
			(end -0.7874 0.4064)
			(stroke
				(width 0.1524)
				(type default)
			)
			(layer "F.SilkS")
		)
		(fp_line
			(start -0.67945 -0.305054)
			(end -0.12065 -0.305054)
			(stroke
				(width 0.1)
				(type default)
			)
			(layer "F.Fab")
		)
		(fp_line
			(start -0.67945 0.3048)
			(end -0.67945 -0.305054)
			(stroke
				(width 0.1)
				(type default)
			)
			(layer "F.Fab")
		)
		(fp_line
			(start -0.12065 -0.305054)
			(end -0.12065 -0.2794)
			(stroke
				(width 0.1)
				(type default)
			)
			(layer "F.Fab")
		)
		(fp_line
			(start -0.12065 -0.2794)
			(end 0.12065 -0.2794)
			(stroke
				(width 0.1)
				(type default)
			)
			(layer "F.Fab")
		)
		(fp_line
			(start -0.12065 0.2794)
			(end -0.12065 0.3048)
			(stroke
				(width 0.1)
				(type default)
			)
			(layer "F.Fab")
		)
		(fp_line
			(start -0.12065 0.3048)
			(end -0.67945 0.3048)
			(stroke
				(width 0.1)
				(type default)
			)
			(layer "F.Fab")
		)
		(fp_line
			(start 0.120396 0.2794)
			(end -0.12065 0.2794)
			(stroke
				(width 0.1)
				(type default)
			)
			(layer "F.Fab")
		)
		(fp_line
			(start 0.120396 0.3048)
			(end 0.120396 0.2794)
			(stroke
				(width 0.1)
				(type default)
			)
			(layer "F.Fab")
		)
		(fp_line
			(start 0.12065 -0.3048)
			(end 0.67945 -0.3048)
			(stroke
				(width 0.1)
				(type default)
			)
			(layer "F.Fab")
		)
		(fp_line
			(start 0.12065 -0.2794)
			(end 0.12065 -0.3048)
			(stroke
				(width 0.1)
				(type default)
			)
			(layer "F.Fab")
		)
		(fp_line
			(start 0.67945 -0.3048)
			(end 0.67945 0.3048)
			(stroke
				(width 0.1)
				(type default)
			)
			(layer "F.Fab")
		)
		(fp_line
			(start 0.67945 0.3048)
			(end 0.120396 0.3048)
			(stroke
				(width 0.1)
				(type default)
			)
			(layer "F.Fab")
		)
		(pad "1" smd circle
			(at -0.40005 0)
			(size 0 0)
			(layers "F.Cu" "F.Mask" "F.Paste")
			(net "I3C_BMC_SWB_R_SCL")
		)
		(pad "2" smd circle
			(at 0.40005 0)
			(size 0 0)
			(layers "F.Cu" "F.Mask" "F.Paste")
			(net "I3C_BMC_SWB_BUF_R_SCL")
		)
	)
	(footprint ""
		(layer "F.Cu")
		(at 24.046942 -417.159948)
		(property "Reference" "R3512"
			(at 0 0 0)
			(layer "F.SilkS")
			(hide yes)
			(effects
				(font
					(size 1.27 1.27)
				)
			)
		)
		(property "Value" ""
			(at 0 0 0)
			(layer "F.Fab")
			(effects
				(font
					(size 1.27 1.27)
				)
			)
		)
		(duplicate_pad_numbers_are_jumpers no)
		(fp_line
			(start -0.7874 -0.4064)
			(end 0.7874 -0.4064)
			(stroke
				(width 0.1524)
				(type default)
			)
			(layer "F.SilkS")
		)
		(fp_line
			(start -0.7874 0.4064)
			(end -0.7874 -0.4064)
			(stroke
				(width 0.1524)
				(type default)
			)
			(layer "F.SilkS")
		)
		(fp_line
			(start 0.7874 -0.4064)
			(end 0.7874 0.4064)
			(stroke
				(width 0.1524)
				(type default)
			)
			(layer "F.SilkS")
		)
		(fp_line
			(start 0.7874 0.4064)
			(end -0.7874 0.4064)
			(stroke
				(width 0.1524)
				(type default)
			)
			(layer "F.SilkS")
		)
		(fp_line
			(start -0.67945 -0.305054)
			(end -0.12065 -0.305054)
			(stroke
				(width 0.1)
				(type default)
			)
			(layer "F.Fab")
		)
		(fp_line
			(start -0.67945 0.3048)
			(end -0.67945 -0.305054)
			(stroke
				(width 0.1)
				(type default)
			)
			(layer "F.Fab")
		)
		(fp_line
			(start -0.12065 -0.305054)
			(end -0.12065 -0.2794)
			(stroke
				(width 0.1)
				(type default)
			)
			(layer "F.Fab")
		)
		(fp_line
			(start -0.12065 -0.2794)
			(end 0.12065 -0.2794)
			(stroke
				(width 0.1)
				(type default)
			)
			(layer "F.Fab")
		)
		(fp_line
			(start -0.12065 0.2794)
			(end -0.12065 0.3048)
			(stroke
				(width 0.1)
				(type default)
			)
			(layer "F.Fab")
		)
		(fp_line
			(start -0.12065 0.3048)
			(end -0.67945 0.3048)
			(stroke
				(width 0.1)
				(type default)
			)
			(layer "F.Fab")
		)
		(fp_line
			(start 0.120396 0.2794)
			(end -0.12065 0.2794)
			(stroke
				(width 0.1)
				(type default)
			)
			(layer "F.Fab")
		)
		(fp_line
			(start 0.120396 0.3048)
			(end 0.120396 0.2794)
			(stroke
				(width 0.1)
				(type default)
			)
			(layer "F.Fab")
		)
		(fp_line
			(start 0.12065 -0.3048)
			(end 0.67945 -0.3048)
			(stroke
				(width 0.1)
				(type default)
			)
			(layer "F.Fab")
		)
		(fp_line
			(start 0.12065 -0.2794)
			(end 0.12065 -0.3048)
			(stroke
				(width 0.1)
				(type default)
			)
			(layer "F.Fab")
		)
		(fp_line
			(start 0.67945 -0.3048)
			(end 0.67945 0.3048)
			(stroke
				(width 0.1)
				(type default)
			)
			(layer "F.Fab")
		)
		(fp_line
			(start 0.67945 0.3048)
			(end 0.120396 0.3048)
			(stroke
				(width 0.1)
				(type default)
			)
			(layer "F.Fab")
		)
		(pad "1" smd circle
			(at -0.40005 0)
			(size 0 0)
			(layers "F.Cu" "F.Mask" "F.Paste")
			(net "P3V3_AUX")
		)
		(pad "2" smd circle
			(at 0.40005 0)
			(size 0 0)
			(layers "F.Cu" "F.Mask" "F.Paste")
			(net "FM_GPU_PWRGD")
		)
	)
	(footprint ""
		(layer "F.Cu")
		(at 432.974496 -109.13745 90)
		(property "Reference" "PR5481"
			(at 0 0 90)
			(layer "F.SilkS")
			(hide yes)
			(effects
				(font
					(size 1.27 1.27)
				)
			)
		)
		(property "Value" ""
			(at 0 0 90)
			(layer "F.Fab")
			(effects
				(font
					(size 1.27 1.27)
				)
			)
		)
		(duplicate_pad_numbers_are_jumpers no)
		(fp_line
			(start 0.7874 -0.4064)
			(end 0.7874 0.4064)
			(stroke
				(width 0.1524)
				(type default)
			)
			(layer "F.SilkS")
		)
		(fp_line
			(start -0.7874 -0.4064)
			(end 0.7874 -0.4064)
			(stroke
				(width 0.1524)
				(type default)
			)
			(layer "F.SilkS")
		)
		(fp_line
			(start 0.7874 0.4064)
			(end -0.7874 0.4064)
			(stroke
				(width 0.1524)
				(type default)
			)
			(layer "F.SilkS")
		)
		(fp_line
			(start -0.7874 0.4064)
			(end -0.7874 -0.4064)
			(stroke
				(width 0.1524)
				(type default)
			)
			(layer "F.SilkS")
		)
		(fp_line
			(start -0.12065 -0.305054)
			(end -0.12065 -0.2794)
			(stroke
				(width 0.1)
				(type default)
			)
			(layer "F.Fab")
		)
		(fp_line
			(start -0.67945 -0.305054)
			(end -0.12065 -0.305054)
			(stroke
				(width 0.1)
				(type default)
			)
			(layer "F.Fab")
		)
		(fp_line
			(start 0.67945 -0.3048)
			(end 0.67945 0.3048)
			(stroke
				(width 0.1)
				(type default)
			)
			(layer "F.Fab")
		)
		(fp_line
			(start 0.12065 -0.3048)
			(end 0.67945 -0.3048)
			(stroke
				(width 0.1)
				(type default)
			)
			(layer "F.Fab")
		)
		(fp_line
			(start 0.12065 -0.2794)
			(end 0.12065 -0.3048)
			(stroke
				(width 0.1)
				(type default)
			)
			(layer "F.Fab")
		)
		(fp_line
			(start -0.12065 -0.2794)
			(end 0.12065 -0.2794)
			(stroke
				(width 0.1)
				(type default)
			)
			(layer "F.Fab")
		)
		(fp_line
			(start 0.120396 0.2794)
			(end -0.12065 0.2794)
			(stroke
				(width 0.1)
				(type default)
			)
			(layer "F.Fab")
		)
		(fp_line
			(start -0.12065 0.2794)
			(end -0.12065 0.3048)
			(stroke
				(width 0.1)
				(type default)
			)
			(layer "F.Fab")
		)
		(fp_line
			(start 0.67945 0.3048)
			(end 0.120396 0.3048)
			(stroke
				(width 0.1)
				(type default)
			)
			(layer "F.Fab")
		)
		(fp_line
			(start 0.120396 0.3048)
			(end 0.120396 0.2794)
			(stroke
				(width 0.1)
				(type default)
			)
			(layer "F.Fab")
		)
		(fp_line
			(start -0.12065 0.3048)
			(end -0.67945 0.3048)
			(stroke
				(width 0.1)
				(type default)
			)
			(layer "F.Fab")
		)
		(fp_line
			(start -0.67945 0.3048)
			(end -0.67945 -0.305054)
			(stroke
				(width 0.1)
				(type default)
			)
			(layer "F.Fab")
		)
		(pad "1" smd circle
			(at -0.40005 0 90)
			(size 0 0)
			(layers "F.Cu" "F.Mask" "F.Paste")
			(net "P3V3_OCP_SENSE_1")
		)
		(pad "2" smd circle
			(at 0.40005 0 90)
			(size 0 0)
			(layers "F.Cu" "F.Mask" "F.Paste")
			(net "GND")
		)
	)
	(footprint ""
		(layer "F.Cu")
		(at 445.760602 -77.829918 90)
		(property "Reference" "PR834"
			(at 0 0 90)
			(layer "F.SilkS")
			(hide yes)
			(effects
				(font
					(size 1.27 1.27)
				)
			)
		)
		(property "Value" ""
			(at 0 0 90)
			(layer "F.Fab")
			(effects
				(font
					(size 1.27 1.27)
				)
			)
		)
		(duplicate_pad_numbers_are_jumpers no)
		(fp_line
			(start 0.7874 -0.4064)
			(end 0.7874 0.4064)
			(stroke
				(width 0.1524)
				(type default)
			)
			(layer "F.SilkS")
		)
		(fp_line
			(start -0.7874 -0.4064)
			(end 0.7874 -0.4064)
			(stroke
				(width 0.1524)
				(type default)
			)
			(layer "F.SilkS")
		)
		(fp_line
			(start 0.7874 0.4064)
			(end -0.7874 0.4064)
			(stroke
				(width 0.1524)
				(type default)
			)
			(layer "F.SilkS")
		)
		(fp_line
			(start -0.7874 0.4064)
			(end -0.7874 -0.4064)
			(stroke
				(width 0.1524)
				(type default)
			)
			(layer "F.SilkS")
		)
		(fp_line
			(start -0.12065 -0.305054)
			(end -0.12065 -0.2794)
			(stroke
				(width 0.1)
				(type default)
			)
			(layer "F.Fab")
		)
		(fp_line
			(start -0.67945 -0.305054)
			(end -0.12065 -0.305054)
			(stroke
				(width 0.1)
				(type default)
			)
			(layer "F.Fab")
		)
		(fp_line
			(start 0.67945 -0.3048)
			(end 0.67945 0.3048)
			(stroke
				(width 0.1)
				(type default)
			)
			(layer "F.Fab")
		)
		(fp_line
			(start 0.12065 -0.3048)
			(end 0.67945 -0.3048)
			(stroke
				(width 0.1)
				(type default)
			)
			(layer "F.Fab")
		)
		(fp_line
			(start 0.12065 -0.2794)
			(end 0.12065 -0.3048)
			(stroke
				(width 0.1)
				(type default)
			)
			(layer "F.Fab")
		)
		(fp_line
			(start -0.12065 -0.2794)
			(end 0.12065 -0.2794)
			(stroke
				(width 0.1)
				(type default)
			)
			(layer "F.Fab")
		)
		(fp_line
			(start 0.120396 0.2794)
			(end -0.12065 0.2794)
			(stroke
				(width 0.1)
				(type default)
			)
			(layer "F.Fab")
		)
		(fp_line
			(start -0.12065 0.2794)
			(end -0.12065 0.3048)
			(stroke
				(width 0.1)
				(type default)
			)
			(layer "F.Fab")
		)
		(fp_line
			(start 0.67945 0.3048)
			(end 0.120396 0.3048)
			(stroke
				(width 0.1)
				(type default)
			)
			(layer "F.Fab")
		)
		(fp_line
			(start 0.120396 0.3048)
			(end 0.120396 0.2794)
			(stroke
				(width 0.1)
				(type default)
			)
			(layer "F.Fab")
		)
		(fp_line
			(start -0.12065 0.3048)
			(end -0.67945 0.3048)
			(stroke
				(width 0.1)
				(type default)
			)
			(layer "F.Fab")
		)
		(fp_line
			(start -0.67945 0.3048)
			(end -0.67945 -0.305054)
			(stroke
				(width 0.1)
				(type default)
			)
			(layer "F.Fab")
		)
		(pad "1" smd circle
			(at -0.40005 0 90)
			(size 0 0)
			(layers "F.Cu" "F.Mask" "F.Paste")
			(net "P3V3_AUX_ILIM")
		)
		(pad "2" smd circle
			(at 0.40005 0 90)
			(size 0 0)
			(layers "F.Cu" "F.Mask" "F.Paste")
			(net "GND")
		)
	)
)
